(kicad_pcb
	(version 20241229)
	(generator "pcbnew")
	(generator_version "9.0")
	(general
		(thickness 1.6642)
		(legacy_teardrops no)
	)
	(paper "A3")
	(title_block
		(title "PolarFire SoM")
		(date "2025-07-22")
		(rev "1.1.4")
		(company "Antmicro Ltd")
		(comment 1 "www.antmicro.com")
		(comment 9 "footprints 118-121 of 470")
	)
	(layers
		(0 "F.Cu" mixed)
		(4 "In1.Cu" power)
		(6 "In2.Cu" signal)
		(8 "In3.Cu" power)
		(10 "In4.Cu" signal)
		(12 "In5.Cu" power)
		(14 "In6.Cu" power)
		(16 "In7.Cu" signal)
		(18 "In8.Cu" power)
		(20 "In9.Cu" signal)
		(22 "In10.Cu" power)
		(24 "In11.Cu" signal)
		(26 "In12.Cu" signal)
		(2 "B.Cu" mixed)
		(9 "F.Adhes" user "F.Adhesive")
		(11 "B.Adhes" user "B.Adhesive")
		(13 "F.Paste" user)
		(15 "B.Paste" user)
		(5 "F.SilkS" user "F.Silkscreen")
		(7 "B.SilkS" user "B.Silkscreen")
		(1 "F.Mask" user)
		(3 "B.Mask" user)
		(17 "Dwgs.User" user "User.Drawings")
		(19 "Cmts.User" user "User.Comments")
		(21 "Eco1.User" user "User.Eco1")
		(23 "Eco2.User" user "User.Eco2")
		(25 "Edge.Cuts" user)
		(27 "Margin" user)
		(31 "F.CrtYd" user "F.Courtyard")
		(29 "B.CrtYd" user "B.Courtyard")
		(35 "F.Fab" user)
		(33 "B.Fab" user)
	)
	(footprint "antmicro-footprints:QFN-24-1EP_4x4mm_P0.5mm_EP2.6x2.6mm"
		(layer "F.Cu")
		(at 214.865 148.05)
		(descr "QFN, 24 Pin (http://ww1.microchip.com/downloads/en/PackagingSpec/00000049BQ.pdf#page=278), generated with kicad-footprint-generator ipc_noLead_generator.py")
		(tags "QFN NoLead")
		(property "Reference" "U28"
			(at 3.185 -0.3 270)
			(layer "F.SilkS")
			(effects
				(font
					(size 0.7 0.7)
					(thickness 0.15)
				)
				(justify left bottom)
			)
		)
		(property "Value" "USB2422-I/MJ"
			(at 0 3.4 0)
			(layer "F.Fab")
			(hide yes)
			(effects
				(font
					(size 0.7 0.7)
					(thickness 0.15)
				)
				(justify left bottom)
			)
		)
		(property "Datasheet" "https://ww1.microchip.com/downloads/aemDocuments/documents/OTH/ProductDocuments/DataSheets/00001726B.pdf"
			(at 0 0 0)
			(layer "F.Fab")
			(hide yes)
			(effects
				(font
					(size 1.27 1.27)
					(thickness 0.15)
				)
			)
		)
		(property "Description" "USB Interface, USB Hub Controller, USB 2.0, 3 V, 3.6 V, SQFN, 24 Pins"
			(at 0 0 0)
			(layer "F.Fab")
			(hide yes)
			(effects
				(font
					(size 1.27 1.27)
					(thickness 0.15)
				)
			)
		)
		(property "Author" "Antmicro"
			(at 0 0 0)
			(layer "F.Fab")
			(hide yes)
			(effects
				(font
					(size 1 1)
					(thickness 0.15)
				)
			)
		)
		(property "License" "Apache-2.0"
			(at 0 0 0)
			(layer "F.Fab")
			(hide yes)
			(effects
				(font
					(size 1 1)
					(thickness 0.15)
				)
			)
		)
		(property "MPN" "USB2422-I/MJ"
			(at 0 0 0)
			(layer "F.Fab")
			(hide yes)
			(effects
				(font
					(size 1 1)
					(thickness 0.15)
				)
			)
		)
		(property "Manufacturer" "Microchip Technology"
			(at 0 0 0)
			(layer "F.Fab")
			(hide yes)
			(effects
				(font
					(size 1 1)
					(thickness 0.15)
				)
			)
		)
		(sheetname "/USB/")
		(sheetfile "usb.kicad_sch")
		(attr smd)
		(fp_line
			(start -2.11 -1.636)
			(end -2.11 -2.11)
			(stroke
				(width 0.15)
				(type solid)
			)
			(layer "F.SilkS")
		)
		(fp_line
			(start -2.11 2.108)
			(end -2.11 1.634)
			(stroke
				(width 0.15)
				(type solid)
			)
			(layer "F.SilkS")
		)
		(fp_line
			(start -1.635 -2.11)
			(end -2.11 -2.11)
			(stroke
				(width 0.15)
				(type solid)
			)
			(layer "F.SilkS")
		)
		(fp_line
			(start -1.635 2.108)
			(end -2.11 2.108)
			(stroke
				(width 0.15)
				(type solid)
			)
			(layer "F.SilkS")
		)
		(fp_line
			(start 1.634 -2.11)
			(end 2.108 -2.11)
			(stroke
				(width 0.15)
				(type solid)
			)
			(layer "F.SilkS")
		)
		(fp_line
			(start 1.634 2.108)
			(end 2.108 2.108)
			(stroke
				(width 0.15)
				(type solid)
			)
			(layer "F.SilkS")
		)
		(fp_line
			(start 2.108 -2.11)
			(end 2.108 -1.635)
			(stroke
				(width 0.15)
				(type solid)
			)
			(layer "F.SilkS")
		)
		(fp_line
			(start 2.108 2.108)
			(end 2.108 1.634)
			(stroke
				(width 0.15)
				(type solid)
			)
			(layer "F.SilkS")
		)
		(fp_circle
			(center -2.3 -2.3)
			(end -2.25 -2.3)
			(stroke
				(width 0.15)
				(type solid)
			)
			(fill yes)
			(layer "F.SilkS")
		)
		(fp_rect
			(start -2.503 -2.503)
			(end 2.5 2.5)
			(stroke
				(width 0.05)
				(type solid)
			)
			(fill no)
			(layer "F.CrtYd")
		)
		(fp_line
			(start -2 -1)
			(end -1 -2)
			(stroke
				(width 0.15)
				(type solid)
			)
			(layer "F.Fab")
		)
		(fp_line
			(start -2 1.999)
			(end -2 -1)
			(stroke
				(width 0.15)
				(type solid)
			)
			(layer "F.Fab")
		)
		(fp_line
			(start -1 -2)
			(end 1.999 -2)
			(stroke
				(width 0.15)
				(type solid)
			)
			(layer "F.Fab")
		)
		(fp_line
			(start 1.999 -2)
			(end 1.999 1.999)
			(stroke
				(width 0.15)
				(type solid)
			)
			(layer "F.Fab")
		)
		(fp_line
			(start 1.999 1.999)
			(end -2 1.999)
			(stroke
				(width 0.15)
				(type solid)
			)
			(layer "F.Fab")
		)
		(fp_text user "License: Apache-2.0"
			(at -2.503 6.6 0)
			(layer "F.Fab")
			(effects
				(font
					(size 0.7 0.7)
					(thickness 0.15)
				)
				(justify left bottom)
			)
		)
		(fp_text user "${REFERENCE}"
			(at -2.503 5.4 0)
			(layer "F.Fab")
			(effects
				(font
					(size 0.7 0.7)
					(thickness 0.15)
				)
				(justify left bottom)
			)
		)
		(fp_text user "Author: Antmicro"
			(at -2.503 7.8 0)
			(layer "F.Fab")
			(effects
				(font
					(size 0.7 0.7)
					(thickness 0.15)
				)
				(justify left bottom)
			)
		)
		(pad "" smd roundrect
			(at -0.652 -0.652)
			(size 1.05 1.05)
			(layers "F.Paste")
			(roundrect_rratio 0.238095)
		)
		(pad "" smd roundrect
			(at -0.652 0.65)
			(size 1.05 1.05)
			(layers "F.Paste")
			(roundrect_rratio 0.238095)
		)
		(pad "" smd roundrect
			(at 0.65 -0.652)
			(size 1.05 1.05)
			(layers "F.Paste")
			(roundrect_rratio 0.238095)
		)
		(pad "" smd roundrect
			(at 0.65 0.65)
			(size 1.05 1.05)
			(layers "F.Paste")
			(roundrect_rratio 0.238095)
		)
		(pad "1" smd roundrect
			(at -1.938 -1.25)
			(size 0.825 0.25)
			(layers "F.Cu" "F.Mask" "F.Paste")
			(roundrect_rratio 0.25)
			(net 50 "+3V3")
			(pinfunction "3V3")
			(pintype "power_in")
		)
		(pad "2" smd roundrect
			(at -1.938 -0.75)
			(size 0.825 0.25)
			(layers "F.Cu" "F.Mask" "F.Paste")
			(roundrect_rratio 0.25)
			(net 122 "/USB/WL_BT.D_N")
			(pinfunction "DN1_D-")
			(pintype "bidirectional")
		)
		(pad "3" smd roundrect
			(at -1.938 -0.25)
			(size 0.825 0.25)
			(layers "F.Cu" "F.Mask" "F.Paste")
			(roundrect_rratio 0.25)
			(net 190 "/USB/WL_BT.D_P")
			(pinfunction "DN1_D+")
			(pintype "bidirectional")
		)
		(pad "4" smd roundrect
			(at -1.938 0.248)
			(size 0.825 0.25)
			(layers "F.Cu" "F.Mask" "F.Paste")
			(roundrect_rratio 0.25)
			(net 514 "/USB/USB_DN1_N")
			(pinfunction "DN2_D-")
			(pintype "bidirectional")
		)
		(pad "5" smd roundrect
			(at -1.938 0.748)
			(size 0.825 0.25)
			(layers "F.Cu" "F.Mask" "F.Paste")
			(roundrect_rratio 0.25)
			(net 515 "/USB/USB_DN1_P")
			(pinfunction "DN2_D+")
			(pintype "bidirectional")
		)
		(pad "6" smd roundrect
			(at -1.938 1.249)
			(size 0.825 0.25)
			(layers "F.Cu" "F.Mask" "F.Paste")
			(roundrect_rratio 0.25)
			(net 233 "unconnected-(U28-NC-Pad6)")
			(pinfunction "NC")
			(pintype "no_connect")
		)
		(pad "7" smd roundrect
			(at -1.25 1.937)
			(size 0.25 0.825)
			(layers "F.Cu" "F.Mask" "F.Paste")
			(roundrect_rratio 0.25)
			(net 234 "unconnected-(U28-PWR_{PRT1}-Pad7)")
			(pinfunction "PWR_{PRT1}")
			(pintype "output+no_connect")
		)
		(pad "8" smd roundrect
			(at -0.75 1.937)
			(size 0.25 0.825)
			(layers "F.Cu" "F.Mask" "F.Paste")
			(roundrect_rratio 0.25)
			(net 239 "unconnected-(U28-OSC_{N1}-Pad8)")
			(pinfunction "OSC_{N1}")
			(pintype "input+no_connect")
		)
		(pad "9" smd roundrect
			(at -0.25 1.937)
			(size 0.25 0.825)
			(layers "F.Cu" "F.Mask" "F.Paste")
			(roundrect_rratio 0.25)
			(net 50 "+3V3")
			(pinfunction "3V3")
			(pintype "passive")
		)
		(pad "10" smd roundrect
			(at 0.248 1.937)
			(size 0.25 0.825)
			(layers "F.Cu" "F.Mask" "F.Paste")
			(roundrect_rratio 0.25)
			(net 182 "Net-(U28-CRFILT)")
			(pinfunction "CRFILT")
			(pintype "passive")
		)
		(pad "11" smd roundrect
			(at 0.748 1.937)
			(size 0.25 0.825)
			(layers "F.Cu" "F.Mask" "F.Paste")
			(roundrect_rratio 0.25)
			(net 242 "unconnected-(U28-PWR_{PRT2}-Pad11)")
			(pinfunction "PWR_{PRT2}")
			(pintype "output+no_connect")
		)
		(pad "12" smd roundrect
			(at 1.249 1.937)
			(size 0.25 0.825)
			(layers "F.Cu" "F.Mask" "F.Paste")
			(roundrect_rratio 0.25)
			(net 244 "unconnected-(U28-OSC_{N2}-Pad12)")
			(pinfunction "OSC_{N2}")
			(pintype "input+no_connect")
		)
		(pad "13" smd roundrect
			(at 1.937 1.249)
			(size 0.825 0.25)
			(layers "F.Cu" "F.Mask" "F.Paste")
			(roundrect_rratio 0.25)
			(net 580 "unconnected-(U28-SMBDATA-Pad13)")
			(pinfunction "SMBDATA")
			(pintype "input+no_connect")
		)
		(pad "14" smd roundrect
			(at 1.937 0.748)
			(size 0.825 0.25)
			(layers "F.Cu" "F.Mask" "F.Paste")
			(roundrect_rratio 0.25)
			(net 581 "unconnected-(U28-SMBCLK-Pad14)")
			(pinfunction "SMBCLK")
			(pintype "input+no_connect")
		)
		(pad "15" smd roundrect
			(at 1.937 0.248)
			(size 0.825 0.25)
			(layers "F.Cu" "F.Mask" "F.Paste")
			(roundrect_rratio 0.25)
			(net 317 "/USB/~{HUB_RST}")
			(pinfunction "~{RESET}")
			(pintype "input")
		)
		(pad "16" smd roundrect
			(at 1.937 -0.25)
			(size 0.825 0.25)
			(layers "F.Cu" "F.Mask" "F.Paste")
			(roundrect_rratio 0.25)
			(net 62 "USB_OTG_ID")
			(pinfunction "VBUS_{DET}")
			(pintype "input")
		)
		(pad "17" smd roundrect
			(at 1.937 -0.75)
			(size 0.825 0.25)
			(layers "F.Cu" "F.Mask" "F.Paste")
			(roundrect_rratio 0.25)
			(net 318 "Net-(U28-SUSP_IND)")
			(pinfunction "SUSP_IND")
			(pintype "input")
		)
		(pad "18" smd roundrect
			(at 1.937 -1.25)
			(size 0.825 0.25)
			(layers "F.Cu" "F.Mask" "F.Paste")
			(roundrect_rratio 0.25)
			(net 50 "+3V3")
			(pinfunction "3V3")
			(pintype "passive")
		)
		(pad "19" smd roundrect
			(at 1.249 -1.938)
			(size 0.25 0.825)
			(layers "F.Cu" "F.Mask" "F.Paste")
			(roundrect_rratio 0.25)
			(net 512 "/USB/USB_UP_N")
			(pinfunction "UP_D-")
			(pintype "bidirectional")
		)
		(pad "20" smd roundrect
			(at 0.748 -1.938)
			(size 0.25 0.825)
			(layers "F.Cu" "F.Mask" "F.Paste")
			(roundrect_rratio 0.25)
			(net 513 "/USB/USB_UP_P")
			(pinfunction "UP_D+")
			(pintype "bidirectional")
		)
		(pad "21" smd roundrect
			(at 0.248 -1.938)
			(size 0.25 0.825)
			(layers "F.Cu" "F.Mask" "F.Paste")
			(roundrect_rratio 0.25)
			(net 247 "unconnected-(U28-XTAL_{OUT}-Pad21)")
			(pinfunction "XTAL_{OUT}")
			(pintype "input+no_connect")
		)
		(pad "22" smd roundrect
			(at -0.25 -1.938)
			(size 0.25 0.825)
			(layers "F.Cu" "F.Mask" "F.Paste")
			(roundrect_rratio 0.25)
			(net 500 "/USB/REF_CLK")
			(pinfunction "XTAL_{IN}")
			(pintype "input")
		)
		(pad "23" smd roundrect
			(at -0.75 -1.938)
			(size 0.25 0.825)
			(layers "F.Cu" "F.Mask" "F.Paste")
			(roundrect_rratio 0.25)
			(net 179 "Net-(U28-PLLFILT)")
			(pinfunction "PLLFILT")
			(pintype "passive")
		)
		(pad "24" smd roundrect
			(at -1.25 -1.938)
			(size 0.25 0.825)
			(layers "F.Cu" "F.Mask" "F.Paste")
			(roundrect_rratio 0.25)
			(net 325 "Net-(U28-R_{BIAS})")
			(pinfunction "R_{BIAS}")
			(pintype "passive")
		)
		(pad "25" smd rect
			(at 0 0)
			(size 2.6 2.6)
			(layers "F.Cu" "F.Mask")
			(net 417 "GND")
			(pinfunction "GND")
			(pintype "power_in")
		)
	)
	(footprint "antmicro-footprints:TP_SMD_0.75mm"
		(layer "F.Cu")
		(at 190.34 148.39)
		(property "Reference" "TP19"
			(at 0 -0.6 0)
			(layer "F.SilkS")
			(hide yes)
			(effects
				(font
					(size 0.7 0.7)
					(thickness 0.15)
				)
				(justify left bottom)
			)
		)
		(property "Value" "TP_0.75mm_SMD"
			(at 0 1.2 0)
			(layer "F.Fab")
			(hide yes)
			(effects
				(font
					(size 0.7 0.7)
					(thickness 0.15)
				)
				(justify left bottom)
			)
		)
		(property "Description" "SMT test point"
			(at 0 0 0)
			(layer "F.Fab")
			(hide yes)
			(effects
				(font
					(size 1.27 1.27)
					(thickness 0.15)
				)
			)
		)
		(property "Author" "Antmicro"
			(at 0 0 0)
			(layer "F.Fab")
			(hide yes)
			(effects
				(font
					(size 1 1)
					(thickness 0.15)
				)
			)
		)
		(property "License" "Apache-2.0"
			(at 0 0 0)
			(layer "F.Fab")
			(hide yes)
			(effects
				(font
					(size 1 1)
					(thickness 0.15)
				)
			)
		)
		(property "MPN" ""
			(at 0 0 0)
			(layer "F.Fab")
			(hide yes)
			(effects
				(font
					(size 1 1)
					(thickness 0.15)
				)
			)
		)
		(property "Manufacturer" ""
			(at 0 0 0)
			(layer "F.Fab")
			(hide yes)
			(effects
				(font
					(size 1 1)
					(thickness 0.15)
				)
			)
		)
		(property "Public" "False"
			(at 0 0 0)
			(layer "F.Fab")
			(hide yes)
			(effects
				(font
					(size 1 1)
					(thickness 0.15)
				)
			)
		)
		(sheetname "/HDMI/")
		(sheetfile "hdmi.kicad_sch")
		(attr exclude_from_pos_files exclude_from_bom)
		(fp_circle
			(center 0 0)
			(end 0.475 0)
			(stroke
				(width 0.05)
				(type default)
			)
			(fill no)
			(layer "F.CrtYd")
		)
		(fp_text user "${REFERENCE}"
			(at -0.4 2.7 0)
			(layer "F.Fab")
			(effects
				(font
					(size 0.7 0.7)
					(thickness 0.15)
				)
				(justify left bottom)
			)
		)
		(fp_text user "License: Apache-2.0"
			(at -0.4 5.101 0)
			(layer "F.Fab")
			(effects
				(font
					(size 0.7 0.7)
					(thickness 0.15)
				)
				(justify left bottom)
			)
		)
		(fp_text user "Author: Antmicro"
			(at -0.4 3.901 0)
			(layer "F.Fab")
			(effects
				(font
					(size 0.7 0.7)
					(thickness 0.15)
				)
				(justify left bottom)
			)
		)
		(pad "1" smd circle
			(at 0 0)
			(size 0.75 0.75)
			(layers "F.Cu" "F.Mask")
			(net 557 "Net-(U15-EQ_S0)")
			(pinfunction "1")
			(pintype "passive")
		)
	)
	(footprint "antmicro-footprints:R_0402_1005Metric"
		(layer "F.Cu")
		(at 181.15 121.45 180)
		(descr "Resistor SMD 0402")
		(tags "resistor SMD 0402")
		(property "Reference" "R12"
			(at -5.1 -6.56 270)
			(layer "F.SilkS")
			(effects
				(font
					(size 0.7 0.7)
					(thickness 0.15)
				)
				(justify left bottom)
			)
		)
		(property "Value" "R_0R_0402"
			(at -1.011843 1.772047 180)
			(layer "F.Fab")
			(hide yes)
			(effects
				(font
					(size 0.7 0.7)
					(thickness 0.15)
				)
				(justify left bottom)
			)
		)
		(property "Datasheet" "https://industrial.panasonic.com/cdbs/www-data/pdf/RDA0000/AOA0000C301.pdf"
			(at 0 0 180)
			(layer "F.Fab")
			(hide yes)
			(effects
				(font
					(size 1.27 1.27)
					(thickness 0.15)
				)
			)
		)
		(property "Description" "SMD Chip Resistor, Jumper, 0 ohm, 100 mW, 0402 [1005 Metric], Thick Film, General Purpose"
			(at 0 0 180)
			(layer "F.Fab")
			(hide yes)
			(effects
				(font
					(size 1.27 1.27)
					(thickness 0.15)
				)
			)
		)
		(property "Author" "Antmicro"
			(at 362.3 242.9 0)
			(layer "F.Fab")
			(hide yes)
			(effects
				(font
					(size 1 1)
					(thickness 0.15)
				)
			)
		)
		(property "Current" "1A"
			(at 362.3 242.9 0)
			(layer "F.Fab")
			(hide yes)
			(effects
				(font
					(size 1 1)
					(thickness 0.15)
				)
			)
		)
		(property "License" "Apache-2.0"
			(at 362.3 242.9 0)
			(layer "F.Fab")
			(hide yes)
			(effects
				(font
					(size 1 1)
					(thickness 0.15)
				)
			)
		)
		(property "MPN" "ERJ2GE0R00X"
			(at 362.3 242.9 0)
			(layer "F.Fab")
			(hide yes)
			(effects
				(font
					(size 1 1)
					(thickness 0.15)
				)
			)
		)
		(property "Manufacturer" "Panasonic"
			(at 362.3 242.9 0)
			(layer "F.Fab")
			(hide yes)
			(effects
				(font
					(size 1 1)
					(thickness 0.15)
				)
			)
		)
		(property "Public" ""
			(at 362.3 242.9 0)
			(layer "F.Fab")
			(hide yes)
			(effects
				(font
					(size 1 1)
					(thickness 0.15)
				)
			)
		)
		(property "Tolerance" "~"
			(at 362.3 242.9 0)
			(layer "F.Fab")
			(hide yes)
			(effects
				(font
					(size 1 1)
					(thickness 0.15)
				)
			)
		)
		(property "Val" "0R"
			(at 362.3 242.9 0)
			(layer "F.Fab")
			(hide yes)
			(effects
				(font
					(size 1 1)
					(thickness 0.15)
				)
			)
		)
		(sheetname "/Ethernet/")
		(sheetfile "ethernet.kicad_sch")
		(attr smd dnp)
		(fp_rect
			(start -0.925 -0.47)
			(end 0.925 0.47)
			(stroke
				(width 0.05)
				(type default)
			)
			(fill no)
			(layer "F.CrtYd")
		)
		(fp_rect
			(start -0.5 -0.25)
			(end 0.5 0.25)
			(stroke
				(width 0.15)
				(type solid)
			)
			(fill no)
			(layer "F.Fab")
		)
		(fp_text user "${REFERENCE}"
			(at -0.95 3.168 180)
			(layer "F.Fab")
			(effects
				(font
					(size 0.7 0.7)
					(thickness 0.15)
				)
				(justify left bottom)
			)
		)
		(fp_text user "Author: Antmicro"
			(at -0.95 4.169 180)
			(layer "F.Fab")
			(effects
				(font
					(size 0.7 0.7)
					(thickness 0.15)
				)
				(justify left bottom)
			)
		)
		(fp_text user "License: Apache-2.0"
			(at -0.95 5.169 180)
			(layer "F.Fab")
			(effects
				(font
					(size 0.7 0.7)
					(thickness 0.15)
				)
				(justify left bottom)
			)
		)
		(pad "1" smd roundrect
			(at -0.48 0 180)
			(size 0.59 0.64)
			(layers "F.Cu" "F.Mask" "F.Paste")
			(roundrect_rratio 0.25)
			(net 125 "JTAG_TDO")
			(pintype "passive")
		)
		(pad "2" smd roundrect
			(at 0.48 0 180)
			(size 0.59 0.64)
			(layers "F.Cu" "F.Mask" "F.Paste")
			(roundrect_rratio 0.25)
			(net 560 "Net-(U11-JTAG_TDO)")
			(pintype "passive")
		)
	)
	(footprint "antmicro-footprints:TP_SMD_0.75mm"
		(layer "F.Cu")
		(at 186.2 146.25 180)
		(property "Reference" "TP35"
			(at 16.68 -0.56 45)
			(layer "F.SilkS")
			(hide yes)
			(effects
				(font
					(size 0.7 0.7)
					(thickness 0.15)
				)
				(justify right bottom)
			)
		)
		(property "Value" "TP_0.75mm_SMD"
			(at 0 1.2 0)
			(layer "F.Fab")
			(hide yes)
			(effects
				(font
					(size 0.7 0.7)
					(thickness 0.15)
				)
				(justify right bottom)
			)
		)
		(property "Description" "SMT test point"
			(at 0 0 180)
			(layer "F.Fab")
			(hide yes)
			(effects
				(font
					(size 1.27 1.27)
					(thickness 0.15)
				)
			)
		)
		(property "Author" "Antmicro"
			(at 372.4 292.5 0)
			(layer "F.Fab")
			(hide yes)
			(effects
				(font
					(size 1 1)
					(thickness 0.15)
				)
			)
		)
		(property "License" "Apache-2.0"
			(at 372.4 292.5 0)
			(layer "F.Fab")
			(hide yes)
			(effects
				(font
					(size 1 1)
					(thickness 0.15)
				)
			)
		)
		(property "MPN" ""
			(at 372.4 292.5 0)
			(layer "F.Fab")
			(hide yes)
			(effects
				(font
					(size 1 1)
					(thickness 0.15)
				)
			)
		)
		(property "Manufacturer" ""
			(at 372.4 292.5 0)
			(layer "F.Fab")
			(hide yes)
			(effects
				(font
					(size 1 1)
					(thickness 0.15)
				)
			)
		)
		(property "Public" "False"
			(at 372.4 292.5 0)
			(layer "F.Fab")
			(hide yes)
			(effects
				(font
					(size 1 1)
					(thickness 0.15)
				)
			)
		)
		(sheetname "/Supply/")
		(sheetfile "supply.kicad_sch")
		(attr exclude_from_pos_files exclude_from_bom)
		(fp_circle
			(center 0 0)
			(end 0.475 0)
			(stroke
				(width 0.05)
				(type default)
			)
			(fill no)
			(layer "F.CrtYd")
		)
		(fp_text user "License: Apache-2.0"
			(at -0.4 5.101 180)
			(layer "F.Fab")
			(effects
				(font
					(size 0.7 0.7)
					(thickness 0.15)
				)
				(justify left bottom)
			)
		)
		(fp_text user "${REFERENCE}"
			(at -0.4 2.7 180)
			(layer "F.Fab")
			(effects
				(font
					(size 0.7 0.7)
					(thickness 0.15)
				)
				(justify left bottom)
			)
		)
		(fp_text user "Author: Antmicro"
			(at -0.4 3.901 180)
			(layer "F.Fab")
			(effects
				(font
					(size 0.7 0.7)
					(thickness 0.15)
				)
				(justify left bottom)
			)
		)
		(pad "1" smd circle
			(at 0 0 180)
			(size 0.75 0.75)
			(layers "F.Cu" "F.Mask")
			(net 47 "+1V05")
			(pinfunction "1")
			(pintype "passive")
		)
	)
)
